(kicad_pcb
	(version 20260206)
	(generator "pcbnew")
	(generator_version "10.0")
	(general
		(thickness 1.6)
		(legacy_teardrops no)
	)
	(paper "A4")
	(title_block
		(title "01162023_DA0F0TEBIF0_F0T_Expander_BD_F_brd_V02_OCP.brd")
		(comment 1 "Grand Teton / footprints 8286-8291 of 9728")
	)
	(layers
		(0 "F.Cu" signal "TOP")
		(4 "In1.Cu" signal "GND")
		(6 "In2.Cu" signal "VCC")
		(8 "In3.Cu" signal "VCC1")
		(10 "In4.Cu" signal "GND1")
		(12 "In5.Cu" signal "IN1")
		(14 "In6.Cu" signal "GND2")
		(16 "In7.Cu" signal "IN2")
		(18 "In8.Cu" signal "GND3")
		(20 "In9.Cu" signal "IN3")
		(22 "In10.Cu" signal "GND4")
		(24 "In11.Cu" signal "IN4")
		(26 "In12.Cu" signal "GND5")
		(28 "In13.Cu" signal "IN5")
		(30 "In14.Cu" signal "GND6")
		(32 "In15.Cu" signal "IN6")
		(34 "In16.Cu" signal "GND7")
		(2 "B.Cu" signal "BOTTOM")
		(9 "F.Adhes" user "F.Adhesive")
		(11 "B.Adhes" user "B.Adhesive")
		(13 "F.Paste" user "Package Geometry/Pastemask Top")
		(15 "B.Paste" user "Package Geometry/Pastemask Bottom")
		(5 "F.SilkS" user "Ref Des/Silkscreen Top")
		(7 "B.SilkS" user "Ref Des/Silkscreen Bottom")
		(1 "F.Mask" user "Board Geometry/Soldermask Top")
		(3 "B.Mask" user "Board Geometry/Soldermask Bottom")
		(17 "Dwgs.User" user "User.Drawings")
		(19 "Cmts.User" user "User.Comments")
		(21 "Eco1.User" user "User.Eco1")
		(23 "Eco2.User" user "User.Eco2")
		(25 "Edge.Cuts" user "Board Geometry/Outline")
		(27 "Margin" user)
		(31 "F.CrtYd" user "Package Geometry/Place Bound Top")
		(29 "B.CrtYd" user "Package Geometry/Place Bound Bottom")
		(35 "F.Fab" user "Ref Des/Assembly Top")
		(33 "B.Fab" user "Ref Des/Assembly Bottom")
	)
	(footprint ""
		(layer "B.Cu")
		(at 230.991664 -207.02016 -90)
		(property "Reference" "R5525"
			(at 0 0 90)
			(layer "B.SilkS")
			(hide yes)
			(effects
				(font
					(size 1.27 1.27)
				)
				(justify mirror)
			)
		)
		(property "Value" ""
			(at 0 0 90)
			(layer "B.Fab")
			(effects
				(font
					(size 1.27 1.27)
				)
				(justify mirror)
			)
		)
		(duplicate_pad_numbers_are_jumpers no)
		(fp_line
			(start -0.7874 0.4064)
			(end 0.7874 0.4064)
			(stroke
				(width 0.1524)
				(type default)
			)
			(layer "B.SilkS")
		)
		(fp_line
			(start 0.7874 0.4064)
			(end 0.7874 -0.4064)
			(stroke
				(width 0.1524)
				(type default)
			)
			(layer "B.SilkS")
		)
		(fp_line
			(start -0.7874 -0.4064)
			(end -0.7874 0.4064)
			(stroke
				(width 0.1524)
				(type default)
			)
			(layer "B.SilkS")
		)
		(fp_line
			(start 0.7874 -0.4064)
			(end -0.7874 -0.4064)
			(stroke
				(width 0.1524)
				(type default)
			)
			(layer "B.SilkS")
		)
		(fp_line
			(start -0.67945 0.3048)
			(end -0.120396 0.3048)
			(stroke
				(width 0.1)
				(type default)
			)
			(layer "B.Fab")
		)
		(fp_line
			(start -0.120396 0.3048)
			(end -0.120396 0.2794)
			(stroke
				(width 0.1)
				(type default)
			)
			(layer "B.Fab")
		)
		(fp_line
			(start 0.12065 0.3048)
			(end 0.67945 0.3048)
			(stroke
				(width 0.1)
				(type default)
			)
			(layer "B.Fab")
		)
		(fp_line
			(start 0.67945 0.3048)
			(end 0.67945 -0.305054)
			(stroke
				(width 0.1)
				(type default)
			)
			(layer "B.Fab")
		)
		(fp_line
			(start -0.120396 0.2794)
			(end 0.12065 0.2794)
			(stroke
				(width 0.1)
				(type default)
			)
			(layer "B.Fab")
		)
		(fp_line
			(start 0.12065 0.2794)
			(end 0.12065 0.3048)
			(stroke
				(width 0.1)
				(type default)
			)
			(layer "B.Fab")
		)
		(fp_line
			(start -0.12065 -0.2794)
			(end -0.12065 -0.3048)
			(stroke
				(width 0.1)
				(type default)
			)
			(layer "B.Fab")
		)
		(fp_line
			(start 0.12065 -0.2794)
			(end -0.12065 -0.2794)
			(stroke
				(width 0.1)
				(type default)
			)
			(layer "B.Fab")
		)
		(fp_line
			(start -0.67945 -0.3048)
			(end -0.67945 0.3048)
			(stroke
				(width 0.1)
				(type default)
			)
			(layer "B.Fab")
		)
		(fp_line
			(start -0.12065 -0.3048)
			(end -0.67945 -0.3048)
			(stroke
				(width 0.1)
				(type default)
			)
			(layer "B.Fab")
		)
		(fp_line
			(start 0.12065 -0.305054)
			(end 0.12065 -0.2794)
			(stroke
				(width 0.1)
				(type default)
			)
			(layer "B.Fab")
		)
		(fp_line
			(start 0.67945 -0.305054)
			(end 0.12065 -0.305054)
			(stroke
				(width 0.1)
				(type default)
			)
			(layer "B.Fab")
		)
		(pad "1" smd circle
			(at 0.40005 0 90)
			(size 0 0)
			(layers "B.Cu" "B.Mask" "B.Paste")
			(net "P3V3_AUX")
		)
		(pad "2" smd circle
			(at -0.40005 0 90)
			(size 0 0)
			(layers "B.Cu" "B.Mask" "B.Paste")
			(net "BIC_FWSPIMISO")
		)
	)
	(footprint ""
		(layer "B.Cu")
		(at 106.223562 -358.724708 90)
		(property "Reference" "R6379"
			(at 0 0 90)
			(layer "B.SilkS")
			(hide yes)
			(effects
				(font
					(size 1.27 1.27)
				)
				(justify mirror)
			)
		)
		(property "Value" ""
			(at 0 0 90)
			(layer "B.Fab")
			(effects
				(font
					(size 1.27 1.27)
				)
				(justify mirror)
			)
		)
		(duplicate_pad_numbers_are_jumpers no)
		(fp_line
			(start 0.7874 -0.4064)
			(end -0.7874 -0.4064)
			(stroke
				(width 0.1524)
				(type default)
			)
			(layer "B.SilkS")
		)
		(fp_line
			(start -0.7874 -0.4064)
			(end -0.7874 0.4064)
			(stroke
				(width 0.1524)
				(type default)
			)
			(layer "B.SilkS")
		)
		(fp_line
			(start 0.7874 0.4064)
			(end 0.7874 -0.4064)
			(stroke
				(width 0.1524)
				(type default)
			)
			(layer "B.SilkS")
		)
		(fp_line
			(start -0.7874 0.4064)
			(end 0.7874 0.4064)
			(stroke
				(width 0.1524)
				(type default)
			)
			(layer "B.SilkS")
		)
		(fp_line
			(start 0.67945 -0.305054)
			(end 0.12065 -0.305054)
			(stroke
				(width 0.1)
				(type default)
			)
			(layer "B.Fab")
		)
		(fp_line
			(start 0.12065 -0.305054)
			(end 0.12065 -0.2794)
			(stroke
				(width 0.1)
				(type default)
			)
			(layer "B.Fab")
		)
		(fp_line
			(start -0.12065 -0.3048)
			(end -0.67945 -0.3048)
			(stroke
				(width 0.1)
				(type default)
			)
			(layer "B.Fab")
		)
		(fp_line
			(start -0.67945 -0.3048)
			(end -0.67945 0.3048)
			(stroke
				(width 0.1)
				(type default)
			)
			(layer "B.Fab")
		)
		(fp_line
			(start 0.12065 -0.2794)
			(end -0.12065 -0.2794)
			(stroke
				(width 0.1)
				(type default)
			)
			(layer "B.Fab")
		)
		(fp_line
			(start -0.12065 -0.2794)
			(end -0.12065 -0.3048)
			(stroke
				(width 0.1)
				(type default)
			)
			(layer "B.Fab")
		)
		(fp_line
			(start 0.12065 0.2794)
			(end 0.12065 0.3048)
			(stroke
				(width 0.1)
				(type default)
			)
			(layer "B.Fab")
		)
		(fp_line
			(start -0.120396 0.2794)
			(end 0.12065 0.2794)
			(stroke
				(width 0.1)
				(type default)
			)
			(layer "B.Fab")
		)
		(fp_line
			(start 0.67945 0.3048)
			(end 0.67945 -0.305054)
			(stroke
				(width 0.1)
				(type default)
			)
			(layer "B.Fab")
		)
		(fp_line
			(start 0.12065 0.3048)
			(end 0.67945 0.3048)
			(stroke
				(width 0.1)
				(type default)
			)
			(layer "B.Fab")
		)
		(fp_line
			(start -0.120396 0.3048)
			(end -0.120396 0.2794)
			(stroke
				(width 0.1)
				(type default)
			)
			(layer "B.Fab")
		)
		(fp_line
			(start -0.67945 0.3048)
			(end -0.120396 0.3048)
			(stroke
				(width 0.1)
				(type default)
			)
			(layer "B.Fab")
		)
		(pad "1" smd circle
			(at 0.40005 0 270)
			(size 0 0)
			(layers "B.Cu" "B.Mask" "B.Paste")
			(net "CLK_100M_DB800ZL_PEX2_S3_R_DN")
		)
		(pad "2" smd circle
			(at -0.40005 0 270)
			(size 0 0)
			(layers "B.Cu" "B.Mask" "B.Paste")
			(net "CLK_100M_DB800ZL_PEX2_S3_DN")
		)
	)
	(footprint ""
		(layer "B.Cu")
		(at 348.526608 -323.146928 -90)
		(property "Reference" "R6508"
			(at 0 0 90)
			(layer "B.SilkS")
			(hide yes)
			(effects
				(font
					(size 1.27 1.27)
				)
				(justify mirror)
			)
		)
		(property "Value" ""
			(at 0 0 90)
			(layer "B.Fab")
			(effects
				(font
					(size 1.27 1.27)
				)
				(justify mirror)
			)
		)
		(duplicate_pad_numbers_are_jumpers no)
		(fp_line
			(start -0.7874 0.4064)
			(end 0.7874 0.4064)
			(stroke
				(width 0.1524)
				(type default)
			)
			(layer "B.SilkS")
		)
		(fp_line
			(start 0.7874 0.4064)
			(end 0.7874 -0.4064)
			(stroke
				(width 0.1524)
				(type default)
			)
			(layer "B.SilkS")
		)
		(fp_line
			(start -0.7874 -0.4064)
			(end -0.7874 0.4064)
			(stroke
				(width 0.1524)
				(type default)
			)
			(layer "B.SilkS")
		)
		(fp_line
			(start 0.7874 -0.4064)
			(end -0.7874 -0.4064)
			(stroke
				(width 0.1524)
				(type default)
			)
			(layer "B.SilkS")
		)
		(fp_line
			(start -0.67945 0.3048)
			(end -0.120396 0.3048)
			(stroke
				(width 0.1)
				(type default)
			)
			(layer "B.Fab")
		)
		(fp_line
			(start -0.120396 0.3048)
			(end -0.120396 0.2794)
			(stroke
				(width 0.1)
				(type default)
			)
			(layer "B.Fab")
		)
		(fp_line
			(start 0.12065 0.3048)
			(end 0.67945 0.3048)
			(stroke
				(width 0.1)
				(type default)
			)
			(layer "B.Fab")
		)
		(fp_line
			(start 0.67945 0.3048)
			(end 0.67945 -0.305054)
			(stroke
				(width 0.1)
				(type default)
			)
			(layer "B.Fab")
		)
		(fp_line
			(start -0.120396 0.2794)
			(end 0.12065 0.2794)
			(stroke
				(width 0.1)
				(type default)
			)
			(layer "B.Fab")
		)
		(fp_line
			(start 0.12065 0.2794)
			(end 0.12065 0.3048)
			(stroke
				(width 0.1)
				(type default)
			)
			(layer "B.Fab")
		)
		(fp_line
			(start -0.12065 -0.2794)
			(end -0.12065 -0.3048)
			(stroke
				(width 0.1)
				(type default)
			)
			(layer "B.Fab")
		)
		(fp_line
			(start 0.12065 -0.2794)
			(end -0.12065 -0.2794)
			(stroke
				(width 0.1)
				(type default)
			)
			(layer "B.Fab")
		)
		(fp_line
			(start -0.67945 -0.3048)
			(end -0.67945 0.3048)
			(stroke
				(width 0.1)
				(type default)
			)
			(layer "B.Fab")
		)
		(fp_line
			(start -0.12065 -0.3048)
			(end -0.67945 -0.3048)
			(stroke
				(width 0.1)
				(type default)
			)
			(layer "B.Fab")
		)
		(fp_line
			(start 0.12065 -0.305054)
			(end 0.12065 -0.2794)
			(stroke
				(width 0.1)
				(type default)
			)
			(layer "B.Fab")
		)
		(fp_line
			(start 0.67945 -0.305054)
			(end 0.12065 -0.305054)
			(stroke
				(width 0.1)
				(type default)
			)
			(layer "B.Fab")
		)
		(pad "1" smd circle
			(at 0.40005 0 90)
			(size 0 0)
			(layers "B.Cu" "B.Mask" "B.Paste")
			(net "P0V8_SERDES_VDDA_PEX2")
		)
		(pad "2" smd circle
			(at -0.40005 0 90)
			(size 0 0)
			(layers "B.Cu" "B.Mask" "B.Paste")
			(net "P0V8_SERDES_VDDA_PEX2_C3")
		)
	)
	(footprint ""
		(layer "B.Cu")
		(at 358.504236 -308.613556 90)
		(property "Reference" "C4359"
			(at 0 0 90)
			(layer "B.SilkS")
			(hide yes)
			(effects
				(font
					(size 1.27 1.27)
				)
				(justify mirror)
			)
		)
		(property "Value" ""
			(at 0 0 90)
			(layer "B.Fab")
			(effects
				(font
					(size 1.27 1.27)
				)
				(justify mirror)
			)
		)
		(duplicate_pad_numbers_are_jumpers no)
		(fp_line
			(start 1.2954 -0.5842)
			(end -1.2954 -0.5842)
			(stroke
				(width 0.1524)
				(type default)
			)
			(layer "B.SilkS")
		)
		(fp_line
			(start -1.2954 -0.5842)
			(end -1.2954 0.5842)
			(stroke
				(width 0.1524)
				(type default)
			)
			(layer "B.SilkS")
		)
		(fp_line
			(start 1.2954 0.5842)
			(end 1.2954 -0.5842)
			(stroke
				(width 0.1524)
				(type default)
			)
			(layer "B.SilkS")
		)
		(fp_line
			(start -1.2954 0.5842)
			(end 1.2954 0.5842)
			(stroke
				(width 0.1524)
				(type default)
			)
			(layer "B.SilkS")
		)
		(fp_line
			(start 0.8636 -0.4572)
			(end -0.8636 -0.4572)
			(stroke
				(width 0.1)
				(type default)
			)
			(layer "B.Fab")
		)
		(fp_line
			(start -0.8636 -0.4572)
			(end -0.8636 -0.4064)
			(stroke
				(width 0.1)
				(type default)
			)
			(layer "B.Fab")
		)
		(fp_line
			(start 1.1938 -0.4064)
			(end 0.8636 -0.4064)
			(stroke
				(width 0.1)
				(type default)
			)
			(layer "B.Fab")
		)
		(fp_line
			(start 0.8636 -0.4064)
			(end 0.8636 -0.4572)
			(stroke
				(width 0.1)
				(type default)
			)
			(layer "B.Fab")
		)
		(fp_line
			(start -0.8636 -0.4064)
			(end -1.1938 -0.4064)
			(stroke
				(width 0.1)
				(type default)
			)
			(layer "B.Fab")
		)
		(fp_line
			(start -1.1938 -0.4064)
			(end -1.1938 0.4064)
			(stroke
				(width 0.1)
				(type default)
			)
			(layer "B.Fab")
		)
		(fp_line
			(start 1.1938 0.4064)
			(end 1.1938 -0.4064)
			(stroke
				(width 0.1)
				(type default)
			)
			(layer "B.Fab")
		)
		(fp_line
			(start 0.8636 0.4064)
			(end 1.1938 0.4064)
			(stroke
				(width 0.1)
				(type default)
			)
			(layer "B.Fab")
		)
		(fp_line
			(start -0.8636 0.4064)
			(end -0.8636 0.4572)
			(stroke
				(width 0.1)
				(type default)
			)
			(layer "B.Fab")
		)
		(fp_line
			(start -1.1938 0.4064)
			(end -0.8636 0.4064)
			(stroke
				(width 0.1)
				(type default)
			)
			(layer "B.Fab")
		)
		(fp_line
			(start 0.8636 0.4572)
			(end 0.8636 0.4064)
			(stroke
				(width 0.1)
				(type default)
			)
			(layer "B.Fab")
		)
		(fp_line
			(start -0.8636 0.4572)
			(end 0.8636 0.4572)
			(stroke
				(width 0.1)
				(type default)
			)
			(layer "B.Fab")
		)
		(pad "1" smd rect
			(at 0.7366 0)
			(size 0.7112 0.8128)
			(layers "B.Cu" "B.Mask" "B.Paste")
			(net "P0V8_PEX3")
		)
		(pad "2" smd rect
			(at -0.7366 0)
			(size 0.7112 0.8128)
			(layers "B.Cu" "B.Mask" "B.Paste")
			(net "GND")
		)
	)
	(footprint ""
		(layer "B.Cu")
		(at 217.647012 -279.586436)
		(property "Reference" "C4290"
			(at 0 0 0)
			(layer "B.SilkS")
			(hide yes)
			(effects
				(font
					(size 1.27 1.27)
				)
				(justify mirror)
			)
		)
		(property "Value" ""
			(at 0 0 0)
			(layer "B.Fab")
			(effects
				(font
					(size 1.27 1.27)
				)
				(justify mirror)
			)
		)
		(duplicate_pad_numbers_are_jumpers no)
		(fp_line
			(start -1.2954 -0.5842)
			(end -1.2954 0.5842)
			(stroke
				(width 0.1524)
				(type default)
			)
			(layer "B.SilkS")
		)
		(fp_line
			(start -1.2954 0.5842)
			(end 1.2954 0.5842)
			(stroke
				(width 0.1524)
				(type default)
			)
			(layer "B.SilkS")
		)
		(fp_line
			(start 1.2954 -0.5842)
			(end -1.2954 -0.5842)
			(stroke
				(width 0.1524)
				(type default)
			)
			(layer "B.SilkS")
		)
		(fp_line
			(start 1.2954 0.5842)
			(end 1.2954 -0.5842)
			(stroke
				(width 0.1524)
				(type default)
			)
			(layer "B.SilkS")
		)
		(fp_line
			(start -1.1938 -0.4064)
			(end -1.1938 0.4064)
			(stroke
				(width 0.1)
				(type default)
			)
			(layer "B.Fab")
		)
		(fp_line
			(start -1.1938 0.4064)
			(end -0.8636 0.4064)
			(stroke
				(width 0.1)
				(type default)
			)
			(layer "B.Fab")
		)
		(fp_line
			(start -0.8636 -0.4572)
			(end -0.8636 -0.4064)
			(stroke
				(width 0.1)
				(type default)
			)
			(layer "B.Fab")
		)
		(fp_line
			(start -0.8636 -0.4064)
			(end -1.1938 -0.4064)
			(stroke
				(width 0.1)
				(type default)
			)
			(layer "B.Fab")
		)
		(fp_line
			(start -0.8636 0.4064)
			(end -0.8636 0.4572)
			(stroke
				(width 0.1)
				(type default)
			)
			(layer "B.Fab")
		)
		(fp_line
			(start -0.8636 0.4572)
			(end 0.8636 0.4572)
			(stroke
				(width 0.1)
				(type default)
			)
			(layer "B.Fab")
		)
		(fp_line
			(start 0.8636 -0.4572)
			(end -0.8636 -0.4572)
			(stroke
				(width 0.1)
				(type default)
			)
			(layer "B.Fab")
		)
		(fp_line
			(start 0.8636 -0.4064)
			(end 0.8636 -0.4572)
			(stroke
				(width 0.1)
				(type default)
			)
			(layer "B.Fab")
		)
		(fp_line
			(start 0.8636 0.4064)
			(end 1.1938 0.4064)
			(stroke
				(width 0.1)
				(type default)
			)
			(layer "B.Fab")
		)
		(fp_line
			(start 0.8636 0.4572)
			(end 0.8636 0.4064)
			(stroke
				(width 0.1)
				(type default)
			)
			(layer "B.Fab")
		)
		(fp_line
			(start 1.1938 -0.4064)
			(end 0.8636 -0.4064)
			(stroke
				(width 0.1)
				(type default)
			)
			(layer "B.Fab")
		)
		(fp_line
			(start 1.1938 0.4064)
			(end 1.1938 -0.4064)
			(stroke
				(width 0.1)
				(type default)
			)
			(layer "B.Fab")
		)
		(pad "1" smd rect
			(at 0.7366 0 270)
			(size 0.7112 0.8128)
			(layers "B.Cu" "B.Mask" "B.Paste")
			(net "P1V25_PEX1")
		)
		(pad "2" smd rect
			(at -0.7366 0 270)
			(size 0.7112 0.8128)
			(layers "B.Cu" "B.Mask" "B.Paste")
			(net "GND")
		)
	)
	(footprint ""
		(layer "B.Cu")
		(at 345.293442 -221.986856 90)
		(property "Reference" "C2048"
			(at 0 0 90)
			(layer "B.SilkS")
			(hide yes)
			(effects
				(font
					(size 1.27 1.27)
				)
				(justify mirror)
			)
		)
		(property "Value" ""
			(at 0 0 90)
			(layer "B.Fab")
			(effects
				(font
					(size 1.27 1.27)
				)
				(justify mirror)
			)
		)
		(duplicate_pad_numbers_are_jumpers no)
		(fp_line
			(start 0.69215 -0.2921)
			(end -0.69215 -0.2921)
			(stroke
				(width 0.1524)
				(type default)
			)
			(layer "B.SilkS")
		)
		(fp_line
			(start -0.69215 -0.2921)
			(end -0.69215 0.2921)
			(stroke
				(width 0.1524)
				(type default)
			)
			(layer "B.SilkS")
		)
		(fp_line
			(start 0.69215 0.2921)
			(end 0.69215 -0.2921)
			(stroke
				(width 0.1524)
				(type default)
			)
			(layer "B.SilkS")
		)
		(fp_line
			(start -0.69215 0.2921)
			(end 0.69215 0.2921)
			(stroke
				(width 0.1524)
				(type default)
			)
			(layer "B.SilkS")
		)
		(fp_line
			(start 0.51435 -0.2794)
			(end -0.51435 -0.2794)
			(stroke
				(width 0.1)
				(type default)
			)
			(layer "B.Fab")
		)
		(fp_line
			(start -0.51435 -0.2794)
			(end -0.51435 0.2794)
			(stroke
				(width 0.1)
				(type default)
			)
			(layer "B.Fab")
		)
		(fp_line
			(start 0.51435 0.2794)
			(end 0.51435 -0.2794)
			(stroke
				(width 0.1)
				(type default)
			)
			(layer "B.Fab")
		)
		(fp_line
			(start -0.51435 0.2794)
			(end 0.51435 0.2794)
			(stroke
				(width 0.1)
				(type default)
			)
			(layer "B.Fab")
		)
		(pad "1" smd circle
			(at 0.40005 0 270)
			(size 0 0)
			(layers "B.Cu" "B.Mask" "B.Paste")
			(net "P3V3_FPGA_VCCIO1")
		)
		(pad "2" smd circle
			(at -0.40005 0 270)
			(size 0 0)
			(layers "B.Cu" "B.Mask" "B.Paste")
			(net "GND")
		)
		(zone
			(layer "B.Cu")
			(hatch none 0.5)
			(connect_pads
				(clearance 0)
			)
			(min_thickness 0.25)
			(keepout
				(tracks not_allowed)
				(vias allowed)
				(pads allowed)
				(copperpour not_allowed)
				(footprints allowed)
			)
			(placement
				(enabled no)
				(sheetname "")
			)
			(fill
				(thermal_gap 0.5)
				(thermal_bridge_width 0.5)
				(island_removal_mode 0)
			)
			(polygon
				(pts
					(xy 345.381072 -222.177356) (xy 345.439238 -222.085916) (xy 345.439238 -221.886526) (xy 345.381072 -221.796356)
					(xy 345.205812 -221.796356) (xy 345.147392 -221.886526) (xy 345.147392 -222.085916) (xy 345.205558 -222.177356)
				)
			)
		)
	)
)
